(kicad_pcb
	(version 20260206)
	(generator "pcbnew")
	(generator_version "10.0")
	(general
		(thickness 1.6)
		(legacy_teardrops no)
	)
	(paper "A4")
	(title_block
		(title "Wiwynn_Tioga_Pass_MB.brd")
		(comment 1 "Tioga Pass / footprints 3151-3158 of 4770")
	)
	(layers
		(0 "F.Cu" signal "TOP")
		(4 "In1.Cu" signal "L2GND")
		(6 "In2.Cu" signal "L3")
		(8 "In3.Cu" signal "L4GND")
		(10 "In4.Cu" signal "L5")
		(12 "In5.Cu" signal "L6GND")
		(14 "In6.Cu" signal "L7VCC")
		(16 "In7.Cu" signal "L8VCC")
		(18 "In8.Cu" signal "L9GND")
		(20 "In9.Cu" signal "L10")
		(22 "In10.Cu" signal "L11GND")
		(24 "In11.Cu" signal "L12")
		(26 "In12.Cu" signal "L13GND")
		(2 "B.Cu" signal "BOTTOM")
		(9 "F.Adhes" user "F.Adhesive")
		(11 "B.Adhes" user "B.Adhesive")
		(13 "F.Paste" user "Package Geometry/Pastemask Top")
		(15 "B.Paste" user "Package Geometry/Pastemask Bottom")
		(5 "F.SilkS" user "Ref Des/Silkscreen Top")
		(7 "B.SilkS" user "Ref Des/Silkscreen Bottom")
		(1 "F.Mask" user "Board Geometry/Soldermask Top")
		(3 "B.Mask" user "Board Geometry/Soldermask Bottom")
		(17 "Dwgs.User" user "User.Drawings")
		(19 "Cmts.User" user "User.Comments")
		(21 "Eco1.User" user "User.Eco1")
		(23 "Eco2.User" user "User.Eco2")
		(25 "Edge.Cuts" user "Board Geometry/Outline")
		(27 "Margin" user)
		(31 "F.CrtYd" user "Package Geometry/Place Bound Top")
		(29 "B.CrtYd" user "Package Geometry/Place Bound Bottom")
		(35 "F.Fab" user "Ref Des/Assembly Top")
		(33 "B.Fab" user "Ref Des/Assembly Bottom")
	)
	(footprint ""
		(layer "B.Cu")
		(at 17.83842 -103.34752 90)
		(property "Reference" "C9N7"
			(at 0 0 90)
			(layer "B.SilkS")
			(hide yes)
			(effects
				(font
					(size 1.27 1.27)
				)
				(justify mirror)
			)
		)
		(property "Value" ""
			(at 0 0 90)
			(layer "B.Fab")
			(effects
				(font
					(size 1.27 1.27)
				)
				(justify mirror)
			)
		)
		(duplicate_pad_numbers_are_jumpers no)
		(fp_poly
			(pts
				(xy -0.3048 -0.1016) (xy -0.3048 0.9906) (xy 0.3048 0.9906) (xy 0.3048 -0.1016)
			)
			(stroke
				(width 0)
				(type default)
			)
			(fill no)
			(layer "B.CrtYd")
		)
		(fp_line
			(start 0.3048 -0.1016)
			(end 0.3048 0.9906)
			(stroke
				(width 0.1)
				(type default)
			)
			(layer "B.Fab")
		)
		(fp_line
			(start -0.3048 -0.1016)
			(end 0.3048 -0.1016)
			(stroke
				(width 0.1)
				(type default)
			)
			(layer "B.Fab")
		)
		(fp_line
			(start 0.3048 0.9906)
			(end -0.3048 0.9906)
			(stroke
				(width 0.1)
				(type default)
			)
			(layer "B.Fab")
		)
		(fp_line
			(start -0.3048 0.9906)
			(end -0.3048 -0.1016)
			(stroke
				(width 0.1)
				(type default)
			)
			(layer "B.Fab")
		)
		(pad "1" smd rect
			(at 0 0 270)
			(size 0.508 0.508)
			(layers "B.Cu" "B.Mask" "B.Paste")
			(net "P3E_CPU1_PE3_MP_C_TXP<15>")
		)
		(pad "2" smd rect
			(at 0 0.889 270)
			(size 0.508 0.508)
			(layers "B.Cu" "B.Mask" "B.Paste")
			(net "P3E_CPU1_PE3_MP_TXP<15>")
		)
		(zone
			(layer "B.Cu")
			(hatch none 0.5)
			(connect_pads
				(clearance 0)
			)
			(min_thickness 0.25)
			(keepout
				(tracks allowed)
				(vias not_allowed)
				(pads allowed)
				(copperpour not_allowed)
				(footprints allowed)
			)
			(placement
				(enabled no)
				(sheetname "")
			)
			(fill
				(thermal_gap 0.5)
				(thermal_bridge_width 0.5)
				(island_removal_mode 0)
			)
			(polygon
				(pts
					(xy 18.09242 -103.60152) (xy 18.09242 -103.09352) (xy 18.47342 -103.09352) (xy 18.47342 -103.60152)
				)
			)
		)
		(zone
			(layer "B.Cu")
			(hatch none 0.5)
			(connect_pads
				(clearance 0)
			)
			(min_thickness 0.25)
			(keepout
				(tracks not_allowed)
				(vias allowed)
				(pads allowed)
				(copperpour not_allowed)
				(footprints allowed)
			)
			(placement
				(enabled no)
				(sheetname "")
			)
			(fill
				(thermal_gap 0.5)
				(thermal_bridge_width 0.5)
				(island_removal_mode 0)
			)
			(polygon
				(pts
					(xy 18.47342 -103.60152) (xy 18.47342 -103.09352) (xy 18.09242 -103.09352) (xy 18.09242 -103.60152)
				)
			)
		)
	)
	(footprint ""
		(layer "B.Cu")
		(at 245.018306 -64.2874 -90)
		(property "Reference" "R5R1"
			(at 0 0 90)
			(layer "B.SilkS")
			(hide yes)
			(effects
				(font
					(size 1.27 1.27)
				)
				(justify mirror)
			)
		)
		(property "Value" ""
			(at 0 0 90)
			(layer "B.Fab")
			(effects
				(font
					(size 1.27 1.27)
				)
				(justify mirror)
			)
		)
		(duplicate_pad_numbers_are_jumpers no)
		(fp_poly
			(pts
				(xy 0.2794 -0.1016) (xy -0.2794 -0.1016) (xy -0.2794 0.9906) (xy 0.2794 0.9906)
			)
			(stroke
				(width 0)
				(type default)
			)
			(fill no)
			(layer "B.CrtYd")
		)
		(fp_line
			(start -0.2794 0.9906)
			(end -0.2794 -0.1016)
			(stroke
				(width 0.1)
				(type default)
			)
			(layer "B.Fab")
		)
		(fp_line
			(start 0.2794 0.9906)
			(end -0.2794 0.9906)
			(stroke
				(width 0.1)
				(type default)
			)
			(layer "B.Fab")
		)
		(fp_line
			(start -0.2794 -0.1016)
			(end 0.2794 -0.1016)
			(stroke
				(width 0.1)
				(type default)
			)
			(layer "B.Fab")
		)
		(fp_line
			(start 0.2794 -0.1016)
			(end 0.2794 0.9906)
			(stroke
				(width 0.1)
				(type default)
			)
			(layer "B.Fab")
		)
		(pad "1" smd rect
			(at 0 0 90)
			(size 0.508 0.508)
			(layers "B.Cu" "B.Mask" "B.Paste")
			(net "PD_CPU0_RSVD_TEST_1")
		)
		(pad "2" smd rect
			(at 0 0.889 90)
			(size 0.508 0.508)
			(layers "B.Cu" "B.Mask" "B.Paste")
			(net "GND")
		)
		(zone
			(layer "B.Cu")
			(hatch none 0.5)
			(connect_pads
				(clearance 0)
			)
			(min_thickness 0.25)
			(keepout
				(tracks not_allowed)
				(vias allowed)
				(pads allowed)
				(copperpour not_allowed)
				(footprints allowed)
			)
			(placement
				(enabled no)
				(sheetname "")
			)
			(fill
				(thermal_gap 0.5)
				(thermal_bridge_width 0.5)
				(island_removal_mode 0)
			)
			(polygon
				(pts
					(xy 244.383306 -64.0334) (xy 244.383306 -64.5414) (xy 244.764306 -64.5414) (xy 244.764306 -64.0334)
				)
			)
		)
		(zone
			(layer "B.Cu")
			(hatch none 0.5)
			(connect_pads
				(clearance 0)
			)
			(min_thickness 0.25)
			(keepout
				(tracks allowed)
				(vias not_allowed)
				(pads allowed)
				(copperpour not_allowed)
				(footprints allowed)
			)
			(placement
				(enabled no)
				(sheetname "")
			)
			(fill
				(thermal_gap 0.5)
				(thermal_bridge_width 0.5)
				(island_removal_mode 0)
			)
			(polygon
				(pts
					(xy 244.764306 -64.0334) (xy 244.764306 -64.5414) (xy 244.383306 -64.5414) (xy 244.383306 -64.0334)
				)
			)
		)
	)
	(footprint ""
		(layer "B.Cu")
		(at 417.576 -8.1915)
		(property "Reference" "R3P51"
			(at 0 0 0)
			(layer "B.SilkS")
			(hide yes)
			(effects
				(font
					(size 1.27 1.27)
				)
				(justify mirror)
			)
		)
		(property "Value" ""
			(at 0 0 0)
			(layer "B.Fab")
			(effects
				(font
					(size 1.27 1.27)
				)
				(justify mirror)
			)
		)
		(duplicate_pad_numbers_are_jumpers no)
		(fp_rect
			(start 0.2794 -0.1016)
			(end -0.2794 0.9906)
			(stroke
				(width 0)
				(type default)
			)
			(fill no)
			(layer "B.CrtYd")
		)
		(fp_line
			(start -0.2794 -0.1016)
			(end 0.2794 -0.1016)
			(stroke
				(width 0.1)
				(type default)
			)
			(layer "B.Fab")
		)
		(fp_line
			(start -0.2794 0.9906)
			(end -0.2794 -0.1016)
			(stroke
				(width 0.1)
				(type default)
			)
			(layer "B.Fab")
		)
		(fp_line
			(start 0.2794 -0.1016)
			(end 0.2794 0.9906)
			(stroke
				(width 0.1)
				(type default)
			)
			(layer "B.Fab")
		)
		(fp_line
			(start 0.2794 0.9906)
			(end -0.2794 0.9906)
			(stroke
				(width 0.1)
				(type default)
			)
			(layer "B.Fab")
		)
		(pad "1" smd rect
			(at 0 0 180)
			(size 0.508 0.508)
			(layers "B.Cu" "B.Mask" "B.Paste")
			(net "VSENSE_P12V_ADM1085")
		)
		(pad "2" smd rect
			(at 0 0.889 180)
			(size 0.508 0.508)
			(layers "B.Cu" "B.Mask" "B.Paste")
			(net "GND")
		)
		(zone
			(layer "B.Cu")
			(hatch none 0.5)
			(connect_pads
				(clearance 0)
			)
			(min_thickness 0.25)
			(keepout
				(tracks not_allowed)
				(vias allowed)
				(pads allowed)
				(copperpour not_allowed)
				(footprints allowed)
			)
			(placement
				(enabled no)
				(sheetname "")
			)
			(fill
				(thermal_gap 0.5)
				(thermal_bridge_width 0.5)
				(island_removal_mode 0)
			)
			(polygon
				(pts
					(xy 417.83 -7.9375) (xy 417.322 -7.9375) (xy 417.322 -7.5565) (xy 417.83 -7.5565)
				)
			)
		)
		(zone
			(layer "B.Cu")
			(hatch none 0.5)
			(connect_pads
				(clearance 0)
			)
			(min_thickness 0.25)
			(keepout
				(tracks allowed)
				(vias not_allowed)
				(pads allowed)
				(copperpour not_allowed)
				(footprints allowed)
			)
			(placement
				(enabled no)
				(sheetname "")
			)
			(fill
				(thermal_gap 0.5)
				(thermal_bridge_width 0.5)
				(island_removal_mode 0)
			)
			(polygon
				(pts
					(xy 417.83 -7.9375) (xy 417.322 -7.9375) (xy 417.322 -7.5565) (xy 417.83 -7.5565)
				)
			)
		)
	)
	(footprint ""
		(layer "B.Cu")
		(at 321.1957 -31.92018 90)
		(property "Reference" "R4T6"
			(at 0 0 90)
			(layer "B.SilkS")
			(hide yes)
			(effects
				(font
					(size 1.27 1.27)
				)
				(justify mirror)
			)
		)
		(property "Value" ""
			(at 0 0 90)
			(layer "B.Fab")
			(effects
				(font
					(size 1.27 1.27)
				)
				(justify mirror)
			)
		)
		(duplicate_pad_numbers_are_jumpers no)
		(fp_poly
			(pts
				(xy 0.2794 -0.1016) (xy -0.2794 -0.1016) (xy -0.2794 0.9906) (xy 0.2794 0.9906)
			)
			(stroke
				(width 0)
				(type default)
			)
			(fill no)
			(layer "B.CrtYd")
		)
		(fp_line
			(start 0.2794 -0.1016)
			(end 0.2794 0.9906)
			(stroke
				(width 0.1)
				(type default)
			)
			(layer "B.Fab")
		)
		(fp_line
			(start -0.2794 -0.1016)
			(end 0.2794 -0.1016)
			(stroke
				(width 0.1)
				(type default)
			)
			(layer "B.Fab")
		)
		(fp_line
			(start 0.2794 0.9906)
			(end -0.2794 0.9906)
			(stroke
				(width 0.1)
				(type default)
			)
			(layer "B.Fab")
		)
		(fp_line
			(start -0.2794 0.9906)
			(end -0.2794 -0.1016)
			(stroke
				(width 0.1)
				(type default)
			)
			(layer "B.Fab")
		)
		(pad "1" smd rect
			(at 0 0 270)
			(size 0.508 0.508)
			(layers "B.Cu" "B.Mask" "B.Paste")
			(net "PVCCIO_CPU0")
		)
		(pad "2" smd rect
			(at 0 0.889 270)
			(size 0.508 0.508)
			(layers "B.Cu" "B.Mask" "B.Paste")
			(net "SMB_DDR_ABC_SDA_G")
		)
		(zone
			(layer "B.Cu")
			(hatch none 0.5)
			(connect_pads
				(clearance 0)
			)
			(min_thickness 0.25)
			(keepout
				(tracks allowed)
				(vias not_allowed)
				(pads allowed)
				(copperpour not_allowed)
				(footprints allowed)
			)
			(placement
				(enabled no)
				(sheetname "")
			)
			(fill
				(thermal_gap 0.5)
				(thermal_bridge_width 0.5)
				(island_removal_mode 0)
			)
			(polygon
				(pts
					(xy 321.4497 -32.17418) (xy 321.4497 -31.66618) (xy 321.8307 -31.66618) (xy 321.8307 -32.17418)
				)
			)
		)
		(zone
			(layer "B.Cu")
			(hatch none 0.5)
			(connect_pads
				(clearance 0)
			)
			(min_thickness 0.25)
			(keepout
				(tracks not_allowed)
				(vias allowed)
				(pads allowed)
				(copperpour not_allowed)
				(footprints allowed)
			)
			(placement
				(enabled no)
				(sheetname "")
			)
			(fill
				(thermal_gap 0.5)
				(thermal_bridge_width 0.5)
				(island_removal_mode 0)
			)
			(polygon
				(pts
					(xy 321.8307 -32.17418) (xy 321.8307 -31.66618) (xy 321.4497 -31.66618) (xy 321.4497 -32.17418)
				)
			)
		)
	)
	(footprint ""
		(layer "B.Cu")
		(at 110.261654 -68.17614 180)
		(property "Reference" "C7P19"
			(at 0 0 0)
			(layer "B.SilkS")
			(hide yes)
			(effects
				(font
					(size 1.27 1.27)
				)
				(justify mirror)
			)
		)
		(property "Value" ""
			(at 0 0 0)
			(layer "B.Fab")
			(effects
				(font
					(size 1.27 1.27)
				)
				(justify mirror)
			)
		)
		(duplicate_pad_numbers_are_jumpers no)
		(fp_poly
			(pts
				(xy 0.7239 -0.2159) (xy -0.7239 -0.2159) (xy -0.7239 1.9939) (xy 0.7239 1.9939)
			)
			(stroke
				(width 0)
				(type default)
			)
			(fill no)
			(layer "B.CrtYd")
		)
		(fp_line
			(start 0.7239 1.9939)
			(end -0.7239 1.9939)
			(stroke
				(width 0.1)
				(type default)
			)
			(layer "B.Fab")
		)
		(fp_line
			(start 0.7239 -0.2159)
			(end 0.7239 1.9939)
			(stroke
				(width 0.1)
				(type default)
			)
			(layer "B.Fab")
		)
		(fp_line
			(start -0.7239 1.9939)
			(end -0.7239 -0.2159)
			(stroke
				(width 0.1)
				(type default)
			)
			(layer "B.Fab")
		)
		(fp_line
			(start -0.7239 -0.2159)
			(end 0.7239 -0.2159)
			(stroke
				(width 0.1)
				(type default)
			)
			(layer "B.Fab")
		)
		(pad "1" smd rect
			(at 0 0)
			(size 1.27 1.016)
			(layers "B.Cu" "B.Mask" "B.Paste")
			(net "PVCCIN_CPU1")
		)
		(pad "2" smd rect
			(at 0 1.778)
			(size 1.27 1.016)
			(layers "B.Cu" "B.Mask" "B.Paste")
			(net "GND")
		)
		(zone
			(layer "B.Cu")
			(hatch none 0.5)
			(connect_pads
				(clearance 0)
			)
			(min_thickness 0.25)
			(keepout
				(tracks not_allowed)
				(vias allowed)
				(pads allowed)
				(copperpour not_allowed)
				(footprints allowed)
			)
			(placement
				(enabled no)
				(sheetname "")
			)
			(fill
				(thermal_gap 0.5)
				(thermal_bridge_width 0.5)
				(island_removal_mode 0)
			)
			(polygon
				(pts
					(xy 109.626654 -68.68414) (xy 110.896654 -68.68414) (xy 110.896654 -69.44614) (xy 109.626654 -69.44614)
				)
			)
		)
	)
	(footprint ""
		(layer "B.Cu")
		(at 273.179286 -77.82814)
		(property "Reference" "C5P19"
			(at 0 0 0)
			(layer "B.SilkS")
			(hide yes)
			(effects
				(font
					(size 1.27 1.27)
				)
				(justify mirror)
			)
		)
		(property "Value" ""
			(at 0 0 0)
			(layer "B.Fab")
			(effects
				(font
					(size 1.27 1.27)
				)
				(justify mirror)
			)
		)
		(duplicate_pad_numbers_are_jumpers no)
		(fp_poly
			(pts
				(xy 0.7239 -0.2159) (xy -0.7239 -0.2159) (xy -0.7239 1.9939) (xy 0.7239 1.9939)
			)
			(stroke
				(width 0)
				(type default)
			)
			(fill no)
			(layer "B.CrtYd")
		)
		(fp_line
			(start -0.7239 -0.2159)
			(end 0.7239 -0.2159)
			(stroke
				(width 0.1)
				(type default)
			)
			(layer "B.Fab")
		)
		(fp_line
			(start -0.7239 1.9939)
			(end -0.7239 -0.2159)
			(stroke
				(width 0.1)
				(type default)
			)
			(layer "B.Fab")
		)
		(fp_line
			(start 0.7239 -0.2159)
			(end 0.7239 1.9939)
			(stroke
				(width 0.1)
				(type default)
			)
			(layer "B.Fab")
		)
		(fp_line
			(start 0.7239 1.9939)
			(end -0.7239 1.9939)
			(stroke
				(width 0.1)
				(type default)
			)
			(layer "B.Fab")
		)
		(pad "1" smd rect
			(at 0 0 180)
			(size 1.27 1.016)
			(layers "B.Cu" "B.Mask" "B.Paste")
			(net "PVCCMCP_CPU0")
		)
		(pad "2" smd rect
			(at 0 1.778 180)
			(size 1.27 1.016)
			(layers "B.Cu" "B.Mask" "B.Paste")
			(net "GND")
		)
		(zone
			(layer "B.Cu")
			(hatch none 0.5)
			(connect_pads
				(clearance 0)
			)
			(min_thickness 0.25)
			(keepout
				(tracks not_allowed)
				(vias allowed)
				(pads allowed)
				(copperpour not_allowed)
				(footprints allowed)
			)
			(placement
				(enabled no)
				(sheetname "")
			)
			(fill
				(thermal_gap 0.5)
				(thermal_bridge_width 0.5)
				(island_removal_mode 0)
			)
			(polygon
				(pts
					(xy 273.814286 -77.32014) (xy 272.544286 -77.32014) (xy 272.544286 -76.55814) (xy 273.814286 -76.55814)
				)
			)
		)
	)
	(footprint ""
		(layer "B.Cu")
		(at 449.6816 -142.8623 90)
		(property "Reference" "R25W159"
			(at 0.8382 -0.67818 90)
			(unlocked yes)
			(layer "B.SilkS")
			(effects
				(font
					(size 0.4064 0.254)
					(thickness 0.1524)
				)
				(justify left mirror)
			)
		)
		(property "Value" ""
			(at 0 0 90)
			(layer "B.Fab")
			(effects
				(font
					(size 1.27 1.27)
				)
				(justify mirror)
			)
		)
		(duplicate_pad_numbers_are_jumpers no)
		(fp_poly
			(pts
				(xy 0.2794 -0.1016) (xy -0.2794 -0.1016) (xy -0.2794 0.9906) (xy 0.2794 0.9906)
			)
			(stroke
				(width 0)
				(type default)
			)
			(fill no)
			(layer "B.CrtYd")
		)
		(fp_line
			(start 0.2794 -0.1016)
			(end 0.2794 0.9906)
			(stroke
				(width 0.1)
				(type default)
			)
			(layer "B.Fab")
		)
		(fp_line
			(start -0.2794 -0.1016)
			(end 0.2794 -0.1016)
			(stroke
				(width 0.1)
				(type default)
			)
			(layer "B.Fab")
		)
		(fp_line
			(start 0.2794 0.9906)
			(end -0.2794 0.9906)
			(stroke
				(width 0.1)
				(type default)
			)
			(layer "B.Fab")
		)
		(fp_line
			(start -0.2794 0.9906)
			(end -0.2794 -0.1016)
			(stroke
				(width 0.1)
				(type default)
			)
			(layer "B.Fab")
		)
		(pad "1" smd rect
			(at 0 0 270)
			(size 0.508 0.508)
			(layers "B.Cu" "B.Mask" "B.Paste")
			(net "GND")
		)
		(pad "2" smd rect
			(at 0 0.889 270)
			(size 0.508 0.508)
			(layers "B.Cu" "B.Mask" "B.Paste")
			(net "PD_GTL2014_3_VREF")
		)
		(zone
			(layer "B.Cu")
			(hatch none 0.5)
			(connect_pads
				(clearance 0)
			)
			(min_thickness 0.25)
			(keepout
				(tracks allowed)
				(vias not_allowed)
				(pads allowed)
				(copperpour not_allowed)
				(footprints allowed)
			)
			(placement
				(enabled no)
				(sheetname "")
			)
			(fill
				(thermal_gap 0.5)
				(thermal_bridge_width 0.5)
				(island_removal_mode 0)
			)
			(polygon
				(pts
					(xy 449.9356 -143.1163) (xy 449.9356 -142.6083) (xy 450.3166 -142.6083) (xy 450.3166 -143.1163)
				)
			)
		)
		(zone
			(layer "B.Cu")
			(hatch none 0.5)
			(connect_pads
				(clearance 0)
			)
			(min_thickness 0.25)
			(keepout
				(tracks not_allowed)
				(vias allowed)
				(pads allowed)
				(copperpour not_allowed)
				(footprints allowed)
			)
			(placement
				(enabled no)
				(sheetname "")
			)
			(fill
				(thermal_gap 0.5)
				(thermal_bridge_width 0.5)
				(island_removal_mode 0)
			)
			(polygon
				(pts
					(xy 450.3166 -143.1163) (xy 450.3166 -142.6083) (xy 449.9356 -142.6083) (xy 449.9356 -143.1163)
				)
			)
		)
	)
	(footprint ""
		(layer "B.Cu")
		(at 405.60371 -37.940234)
		(property "Reference" "R2T41"
			(at 0.8382 -0.67818 0)
			(unlocked yes)
			(layer "B.SilkS")
			(effects
				(font
					(size 0.4064 0.254)
					(thickness 0.1524)
				)
				(justify left mirror)
			)
		)
		(property "Value" ""
			(at 0 0 0)
			(layer "B.Fab")
			(effects
				(font
					(size 1.27 1.27)
				)
				(justify mirror)
			)
		)
		(duplicate_pad_numbers_are_jumpers no)
		(fp_poly
			(pts
				(xy 0.2794 -0.1016) (xy -0.2794 -0.1016) (xy -0.2794 0.9906) (xy 0.2794 0.9906)
			)
			(stroke
				(width 0)
				(type default)
			)
			(fill no)
			(layer "B.CrtYd")
		)
		(fp_line
			(start -0.2794 -0.1016)
			(end 0.2794 -0.1016)
			(stroke
				(width 0.1)
				(type default)
			)
			(layer "B.Fab")
		)
		(fp_line
			(start -0.2794 0.9906)
			(end -0.2794 -0.1016)
			(stroke
				(width 0.1)
				(type default)
			)
			(layer "B.Fab")
		)
		(fp_line
			(start 0.2794 -0.1016)
			(end 0.2794 0.9906)
			(stroke
				(width 0.1)
				(type default)
			)
			(layer "B.Fab")
		)
		(fp_line
			(start 0.2794 0.9906)
			(end -0.2794 0.9906)
			(stroke
				(width 0.1)
				(type default)
			)
			(layer "B.Fab")
		)
		(pad "1" smd rect
			(at 0 0 180)
			(size 0.508 0.508)
			(layers "B.Cu" "B.Mask" "B.Paste")
			(net "IRQ_FORCE_NM_THROTTLE_N")
		)
		(pad "2" smd rect
			(at 0 0.889 180)
			(size 0.508 0.508)
			(layers "B.Cu" "B.Mask" "B.Paste")
			(net "FM_BMC_SYS_THROTTLE_R_N")
		)
		(zone
			(layer "B.Cu")
			(hatch none 0.5)
			(connect_pads
				(clearance 0)
			)
			(min_thickness 0.25)
			(keepout
				(tracks allowed)
				(vias not_allowed)
				(pads allowed)
				(copperpour not_allowed)
				(footprints allowed)
			)
			(placement
				(enabled no)
				(sheetname "")
			)
			(fill
				(thermal_gap 0.5)
				(thermal_bridge_width 0.5)
				(island_removal_mode 0)
			)
			(polygon
				(pts
					(xy 405.85771 -37.686234) (xy 405.34971 -37.686234) (xy 405.34971 -37.305234) (xy 405.85771 -37.305234)
				)
			)
		)
		(zone
			(layer "B.Cu")
			(hatch none 0.5)
			(connect_pads
				(clearance 0)
			)
			(min_thickness 0.25)
			(keepout
				(tracks not_allowed)
				(vias allowed)
				(pads allowed)
				(copperpour not_allowed)
				(footprints allowed)
			)
			(placement
				(enabled no)
				(sheetname "")
			)
			(fill
				(thermal_gap 0.5)
				(thermal_bridge_width 0.5)
				(island_removal_mode 0)
			)
			(polygon
				(pts
					(xy 405.85771 -37.305234) (xy 405.34971 -37.305234) (xy 405.34971 -37.686234) (xy 405.85771 -37.686234)
				)
			)
		)
	)
)
